(kicad_pcb
	(version 20260206)
	(generator "pcbnew")
	(generator_version "10.0")
	(general
		(thickness 1.6)
		(legacy_teardrops no)
	)
	(paper "A4")
	(title_block
		(title "01162023_DA0F0TEBIF0_F0T_Expander_BD_F_brd_V02_OCP.brd")
		(comment 1 "Grand Teton / footprints 6863-6870 of 9728")
	)
	(layers
		(0 "F.Cu" signal "TOP")
		(4 "In1.Cu" signal "GND")
		(6 "In2.Cu" signal "VCC")
		(8 "In3.Cu" signal "VCC1")
		(10 "In4.Cu" signal "GND1")
		(12 "In5.Cu" signal "IN1")
		(14 "In6.Cu" signal "GND2")
		(16 "In7.Cu" signal "IN2")
		(18 "In8.Cu" signal "GND3")
		(20 "In9.Cu" signal "IN3")
		(22 "In10.Cu" signal "GND4")
		(24 "In11.Cu" signal "IN4")
		(26 "In12.Cu" signal "GND5")
		(28 "In13.Cu" signal "IN5")
		(30 "In14.Cu" signal "GND6")
		(32 "In15.Cu" signal "IN6")
		(34 "In16.Cu" signal "GND7")
		(2 "B.Cu" signal "BOTTOM")
		(9 "F.Adhes" user "F.Adhesive")
		(11 "B.Adhes" user "B.Adhesive")
		(13 "F.Paste" user "Package Geometry/Pastemask Top")
		(15 "B.Paste" user "Package Geometry/Pastemask Bottom")
		(5 "F.SilkS" user "Ref Des/Silkscreen Top")
		(7 "B.SilkS" user "Ref Des/Silkscreen Bottom")
		(1 "F.Mask" user "Board Geometry/Soldermask Top")
		(3 "B.Mask" user "Board Geometry/Soldermask Bottom")
		(17 "Dwgs.User" user "User.Drawings")
		(19 "Cmts.User" user "User.Comments")
		(21 "Eco1.User" user "User.Eco1")
		(23 "Eco2.User" user "User.Eco2")
		(25 "Edge.Cuts" user "Board Geometry/Outline")
		(27 "Margin" user)
		(31 "F.CrtYd" user "Package Geometry/Place Bound Top")
		(29 "B.CrtYd" user "Package Geometry/Place Bound Bottom")
		(35 "F.Fab" user "Ref Des/Assembly Top")
		(33 "B.Fab" user "Ref Des/Assembly Bottom")
	)
	(footprint ""
		(layer "F.Cu")
		(at 214.587582 -25.342342 -90)
		(property "Reference" "R432"
			(at 0 0 270)
			(layer "F.SilkS")
			(hide yes)
			(effects
				(font
					(size 1.27 1.27)
				)
			)
		)
		(property "Value" ""
			(at 0 0 270)
			(layer "F.Fab")
			(effects
				(font
					(size 1.27 1.27)
				)
			)
		)
		(duplicate_pad_numbers_are_jumpers no)
		(fp_line
			(start -0.7874 0.4064)
			(end -0.7874 -0.4064)
			(stroke
				(width 0.1524)
				(type default)
			)
			(layer "F.SilkS")
		)
		(fp_line
			(start 0.7874 0.4064)
			(end -0.7874 0.4064)
			(stroke
				(width 0.1524)
				(type default)
			)
			(layer "F.SilkS")
		)
		(fp_line
			(start -0.7874 -0.4064)
			(end 0.7874 -0.4064)
			(stroke
				(width 0.1524)
				(type default)
			)
			(layer "F.SilkS")
		)
		(fp_line
			(start 0.7874 -0.4064)
			(end 0.7874 0.4064)
			(stroke
				(width 0.1524)
				(type default)
			)
			(layer "F.SilkS")
		)
		(fp_line
			(start -0.67945 0.3048)
			(end -0.67945 -0.305054)
			(stroke
				(width 0.1)
				(type default)
			)
			(layer "F.Fab")
		)
		(fp_line
			(start -0.12065 0.3048)
			(end -0.67945 0.3048)
			(stroke
				(width 0.1)
				(type default)
			)
			(layer "F.Fab")
		)
		(fp_line
			(start 0.120396 0.3048)
			(end 0.120396 0.2794)
			(stroke
				(width 0.1)
				(type default)
			)
			(layer "F.Fab")
		)
		(fp_line
			(start 0.67945 0.3048)
			(end 0.120396 0.3048)
			(stroke
				(width 0.1)
				(type default)
			)
			(layer "F.Fab")
		)
		(fp_line
			(start -0.12065 0.2794)
			(end -0.12065 0.3048)
			(stroke
				(width 0.1)
				(type default)
			)
			(layer "F.Fab")
		)
		(fp_line
			(start 0.120396 0.2794)
			(end -0.12065 0.2794)
			(stroke
				(width 0.1)
				(type default)
			)
			(layer "F.Fab")
		)
		(fp_line
			(start -0.12065 -0.2794)
			(end 0.12065 -0.2794)
			(stroke
				(width 0.1)
				(type default)
			)
			(layer "F.Fab")
		)
		(fp_line
			(start 0.12065 -0.2794)
			(end 0.12065 -0.3048)
			(stroke
				(width 0.1)
				(type default)
			)
			(layer "F.Fab")
		)
		(fp_line
			(start 0.12065 -0.3048)
			(end 0.67945 -0.3048)
			(stroke
				(width 0.1)
				(type default)
			)
			(layer "F.Fab")
		)
		(fp_line
			(start 0.67945 -0.3048)
			(end 0.67945 0.3048)
			(stroke
				(width 0.1)
				(type default)
			)
			(layer "F.Fab")
		)
		(fp_line
			(start -0.67945 -0.305054)
			(end -0.12065 -0.305054)
			(stroke
				(width 0.1)
				(type default)
			)
			(layer "F.Fab")
		)
		(fp_line
			(start -0.12065 -0.305054)
			(end -0.12065 -0.2794)
			(stroke
				(width 0.1)
				(type default)
			)
			(layer "F.Fab")
		)
		(pad "1" smd circle
			(at -0.40005 0 270)
			(size 0 0)
			(layers "F.Cu" "F.Mask" "F.Paste")
			(net "GND")
		)
		(pad "2" smd circle
			(at 0.40005 0 270)
			(size 0 0)
			(layers "F.Cu" "F.Mask" "F.Paste")
			(net "DUALPORT_N_SSD7")
		)
	)
	(footprint ""
		(layer "F.Cu")
		(at 124.311156 -61.386974)
		(property "Reference" "R4483"
			(at 0 0 0)
			(layer "F.SilkS")
			(hide yes)
			(effects
				(font
					(size 1.27 1.27)
				)
			)
		)
		(property "Value" ""
			(at 0 0 0)
			(layer "F.Fab")
			(effects
				(font
					(size 1.27 1.27)
				)
			)
		)
		(duplicate_pad_numbers_are_jumpers no)
		(fp_line
			(start -0.7874 -0.4064)
			(end 0.7874 -0.4064)
			(stroke
				(width 0.1524)
				(type default)
			)
			(layer "F.SilkS")
		)
		(fp_line
			(start -0.7874 0.4064)
			(end -0.7874 -0.4064)
			(stroke
				(width 0.1524)
				(type default)
			)
			(layer "F.SilkS")
		)
		(fp_line
			(start 0.7874 -0.4064)
			(end 0.7874 0.4064)
			(stroke
				(width 0.1524)
				(type default)
			)
			(layer "F.SilkS")
		)
		(fp_line
			(start 0.7874 0.4064)
			(end -0.7874 0.4064)
			(stroke
				(width 0.1524)
				(type default)
			)
			(layer "F.SilkS")
		)
		(fp_line
			(start -0.67945 -0.305054)
			(end -0.12065 -0.305054)
			(stroke
				(width 0.1)
				(type default)
			)
			(layer "F.Fab")
		)
		(fp_line
			(start -0.67945 0.3048)
			(end -0.67945 -0.305054)
			(stroke
				(width 0.1)
				(type default)
			)
			(layer "F.Fab")
		)
		(fp_line
			(start -0.12065 -0.305054)
			(end -0.12065 -0.2794)
			(stroke
				(width 0.1)
				(type default)
			)
			(layer "F.Fab")
		)
		(fp_line
			(start -0.12065 -0.2794)
			(end 0.12065 -0.2794)
			(stroke
				(width 0.1)
				(type default)
			)
			(layer "F.Fab")
		)
		(fp_line
			(start -0.12065 0.2794)
			(end -0.12065 0.3048)
			(stroke
				(width 0.1)
				(type default)
			)
			(layer "F.Fab")
		)
		(fp_line
			(start -0.12065 0.3048)
			(end -0.67945 0.3048)
			(stroke
				(width 0.1)
				(type default)
			)
			(layer "F.Fab")
		)
		(fp_line
			(start 0.120396 0.2794)
			(end -0.12065 0.2794)
			(stroke
				(width 0.1)
				(type default)
			)
			(layer "F.Fab")
		)
		(fp_line
			(start 0.120396 0.3048)
			(end 0.120396 0.2794)
			(stroke
				(width 0.1)
				(type default)
			)
			(layer "F.Fab")
		)
		(fp_line
			(start 0.12065 -0.3048)
			(end 0.67945 -0.3048)
			(stroke
				(width 0.1)
				(type default)
			)
			(layer "F.Fab")
		)
		(fp_line
			(start 0.12065 -0.2794)
			(end 0.12065 -0.3048)
			(stroke
				(width 0.1)
				(type default)
			)
			(layer "F.Fab")
		)
		(fp_line
			(start 0.67945 -0.3048)
			(end 0.67945 0.3048)
			(stroke
				(width 0.1)
				(type default)
			)
			(layer "F.Fab")
		)
		(fp_line
			(start 0.67945 0.3048)
			(end 0.120396 0.3048)
			(stroke
				(width 0.1)
				(type default)
			)
			(layer "F.Fab")
		)
		(pad "1" smd circle
			(at -0.40005 0)
			(size 0 0)
			(layers "F.Cu" "F.Mask" "F.Paste")
			(net "PWRGD_P3V3_SSD4")
		)
		(pad "2" smd circle
			(at 0.40005 0)
			(size 0 0)
			(layers "F.Cu" "F.Mask" "F.Paste")
			(net "PWRGD_P3V3_SSD4_R")
		)
	)
	(footprint ""
		(layer "F.Cu")
		(at 16.785336 -275.248624)
		(property "Reference" "R772"
			(at 0 0 0)
			(layer "F.SilkS")
			(hide yes)
			(effects
				(font
					(size 1.27 1.27)
				)
			)
		)
		(property "Value" ""
			(at 0 0 0)
			(layer "F.Fab")
			(effects
				(font
					(size 1.27 1.27)
				)
			)
		)
		(duplicate_pad_numbers_are_jumpers no)
		(fp_line
			(start -0.7874 -0.4064)
			(end 0.7874 -0.4064)
			(stroke
				(width 0.1524)
				(type default)
			)
			(layer "F.SilkS")
		)
		(fp_line
			(start -0.7874 0.4064)
			(end -0.7874 -0.4064)
			(stroke
				(width 0.1524)
				(type default)
			)
			(layer "F.SilkS")
		)
		(fp_line
			(start 0.7874 -0.4064)
			(end 0.7874 0.4064)
			(stroke
				(width 0.1524)
				(type default)
			)
			(layer "F.SilkS")
		)
		(fp_line
			(start 0.7874 0.4064)
			(end -0.7874 0.4064)
			(stroke
				(width 0.1524)
				(type default)
			)
			(layer "F.SilkS")
		)
		(fp_line
			(start -0.67945 -0.305054)
			(end -0.12065 -0.305054)
			(stroke
				(width 0.1)
				(type default)
			)
			(layer "F.Fab")
		)
		(fp_line
			(start -0.67945 0.3048)
			(end -0.67945 -0.305054)
			(stroke
				(width 0.1)
				(type default)
			)
			(layer "F.Fab")
		)
		(fp_line
			(start -0.12065 -0.305054)
			(end -0.12065 -0.2794)
			(stroke
				(width 0.1)
				(type default)
			)
			(layer "F.Fab")
		)
		(fp_line
			(start -0.12065 -0.2794)
			(end 0.12065 -0.2794)
			(stroke
				(width 0.1)
				(type default)
			)
			(layer "F.Fab")
		)
		(fp_line
			(start -0.12065 0.2794)
			(end -0.12065 0.3048)
			(stroke
				(width 0.1)
				(type default)
			)
			(layer "F.Fab")
		)
		(fp_line
			(start -0.12065 0.3048)
			(end -0.67945 0.3048)
			(stroke
				(width 0.1)
				(type default)
			)
			(layer "F.Fab")
		)
		(fp_line
			(start 0.120396 0.2794)
			(end -0.12065 0.2794)
			(stroke
				(width 0.1)
				(type default)
			)
			(layer "F.Fab")
		)
		(fp_line
			(start 0.120396 0.3048)
			(end 0.120396 0.2794)
			(stroke
				(width 0.1)
				(type default)
			)
			(layer "F.Fab")
		)
		(fp_line
			(start 0.12065 -0.3048)
			(end 0.67945 -0.3048)
			(stroke
				(width 0.1)
				(type default)
			)
			(layer "F.Fab")
		)
		(fp_line
			(start 0.12065 -0.2794)
			(end 0.12065 -0.3048)
			(stroke
				(width 0.1)
				(type default)
			)
			(layer "F.Fab")
		)
		(fp_line
			(start 0.67945 -0.3048)
			(end 0.67945 0.3048)
			(stroke
				(width 0.1)
				(type default)
			)
			(layer "F.Fab")
		)
		(fp_line
			(start 0.67945 0.3048)
			(end 0.120396 0.3048)
			(stroke
				(width 0.1)
				(type default)
			)
			(layer "F.Fab")
		)
		(pad "1" smd circle
			(at -0.40005 0)
			(size 0 0)
			(layers "F.Cu" "F.Mask" "F.Paste")
			(net "PEX0_P1V25_ADC_ALERT_N")
		)
		(pad "2" smd circle
			(at 0.40005 0)
			(size 0 0)
			(layers "F.Cu" "F.Mask" "F.Paste")
			(net "PEX_ADC_ALERT_N")
		)
	)
	(footprint ""
		(layer "F.Cu")
		(at 276.820122 -15.649956 180)
		(property "Reference" "H120"
			(at -1.255776 2.800096 0)
			(unlocked yes)
			(layer "B.SilkS")
			(effects
				(font
					(size 0.7874 0.5842)
					(thickness 0.1524)
				)
				(justify left mirror)
			)
		)
		(property "Value" ""
			(at 0 0 180)
			(layer "F.Fab")
			(effects
				(font
					(size 1.27 1.27)
				)
			)
		)
		(duplicate_pad_numbers_are_jumpers no)
		(pad "1" thru_hole rect
			(at 0 0 180)
			(size 4.2164 5.0038)
			(drill 2.0066
				(offset 0.099822 0)
			)
			(layers "*.Cu" "*.Mask")
			(remove_unused_layers no)
			(net "Net_8543")
			(clearance -0.8509)
			(padstack
				(mode front_inner_back)
				(layer "Inner"
					(shape circle)
					(size 4.0132 4.0132)
					(clearance -0.7493)
				)
				(layer "B.Cu"
					(shape circle)
					(size 4.0132 4.0132)
					(clearance -0.7493)
				)
			)
		)
	)
	(footprint ""
		(layer "F.Cu")
		(at 474.236288 -552.440348 180)
		(property "Reference" "J43_OTH"
			(at -3.2385 -1.402334 0)
			(unlocked yes)
			(layer "B.SilkS")
			(effects
				(font
					(size 0.7874 0.5842)
					(thickness 0.1524)
				)
				(justify mirror)
			)
		)
		(property "Value" ""
			(at 0 0 180)
			(layer "F.Fab")
			(effects
				(font
					(size 1.27 1.27)
				)
			)
		)
		(duplicate_pad_numbers_are_jumpers no)
		(pad "1" thru_hole circle
			(at 0 0 180)
			(size 0.4572 0.4572)
			(drill 0.2032)
			(layers "*.Cu" "*.Mask")
			(remove_unused_layers no)
			(net "Net_9093")
			(clearance 0.127)
			(thermal_gap 0.127)
			(padstack
				(mode front_inner_back)
				(layer "Inner"
					(shape circle)
					(size 0.4572 0.4572)
					(clearance 0.127)
				)
				(layer "B.Cu"
					(shape circle)
					(size 0.508 0.508)
					(clearance 0.1016)
				)
			)
		)
	)
	(footprint ""
		(layer "F.Cu")
		(at 162.773106 -22.867366 90)
		(property "Reference" "C3907"
			(at 0 0 90)
			(layer "F.SilkS")
			(hide yes)
			(effects
				(font
					(size 1.27 1.27)
				)
			)
		)
		(property "Value" ""
			(at 0 0 90)
			(layer "F.Fab")
			(effects
				(font
					(size 1.27 1.27)
				)
			)
		)
		(duplicate_pad_numbers_are_jumpers no)
		(fp_line
			(start 0.7874 -0.4064)
			(end 0.7874 0.4064)
			(stroke
				(width 0.1524)
				(type default)
			)
			(layer "F.SilkS")
		)
		(fp_line
			(start -0.7874 -0.4064)
			(end 0.7874 -0.4064)
			(stroke
				(width 0.1524)
				(type default)
			)
			(layer "F.SilkS")
		)
		(fp_line
			(start 0.7874 0.4064)
			(end -0.7874 0.4064)
			(stroke
				(width 0.1524)
				(type default)
			)
			(layer "F.SilkS")
		)
		(fp_line
			(start -0.7874 0.4064)
			(end -0.7874 -0.4064)
			(stroke
				(width 0.1524)
				(type default)
			)
			(layer "F.SilkS")
		)
		(fp_line
			(start -0.12065 -0.305054)
			(end -0.12065 -0.2794)
			(stroke
				(width 0.1)
				(type default)
			)
			(layer "F.Fab")
		)
		(fp_line
			(start -0.67945 -0.305054)
			(end -0.12065 -0.305054)
			(stroke
				(width 0.1)
				(type default)
			)
			(layer "F.Fab")
		)
		(fp_line
			(start 0.67945 -0.3048)
			(end 0.67945 0.3048)
			(stroke
				(width 0.1)
				(type default)
			)
			(layer "F.Fab")
		)
		(fp_line
			(start 0.12065 -0.3048)
			(end 0.67945 -0.3048)
			(stroke
				(width 0.1)
				(type default)
			)
			(layer "F.Fab")
		)
		(fp_line
			(start 0.12065 -0.2794)
			(end 0.12065 -0.3048)
			(stroke
				(width 0.1)
				(type default)
			)
			(layer "F.Fab")
		)
		(fp_line
			(start -0.12065 -0.2794)
			(end 0.12065 -0.2794)
			(stroke
				(width 0.1)
				(type default)
			)
			(layer "F.Fab")
		)
		(fp_line
			(start 0.120396 0.2794)
			(end -0.12065 0.2794)
			(stroke
				(width 0.1)
				(type default)
			)
			(layer "F.Fab")
		)
		(fp_line
			(start -0.12065 0.2794)
			(end -0.12065 0.3048)
			(stroke
				(width 0.1)
				(type default)
			)
			(layer "F.Fab")
		)
		(fp_line
			(start 0.67945 0.3048)
			(end 0.120396 0.3048)
			(stroke
				(width 0.1)
				(type default)
			)
			(layer "F.Fab")
		)
		(fp_line
			(start 0.120396 0.3048)
			(end 0.120396 0.2794)
			(stroke
				(width 0.1)
				(type default)
			)
			(layer "F.Fab")
		)
		(fp_line
			(start -0.12065 0.3048)
			(end -0.67945 0.3048)
			(stroke
				(width 0.1)
				(type default)
			)
			(layer "F.Fab")
		)
		(fp_line
			(start -0.67945 0.3048)
			(end -0.67945 -0.305054)
			(stroke
				(width 0.1)
				(type default)
			)
			(layer "F.Fab")
		)
		(pad "1" smd circle
			(at -0.40005 0 90)
			(size 0 0)
			(layers "F.Cu" "F.Mask" "F.Paste")
			(net "P12V_SSD5")
		)
		(pad "2" smd circle
			(at 0.40005 0 90)
			(size 0 0)
			(layers "F.Cu" "F.Mask" "F.Paste")
			(net "GND")
		)
	)
	(footprint ""
		(layer "F.Cu")
		(at 319.609724 -356.244906 90)
		(property "Reference" "C558"
			(at 0 0 90)
			(layer "F.SilkS")
			(hide yes)
			(effects
				(font
					(size 1.27 1.27)
				)
			)
		)
		(property "Value" ""
			(at 0 0 90)
			(layer "F.Fab")
			(effects
				(font
					(size 1.27 1.27)
				)
			)
		)
		(duplicate_pad_numbers_are_jumpers no)
		(fp_line
			(start 0.299974 -0.150114)
			(end 0.299974 0.150114)
			(stroke
				(width 0.1)
				(type default)
			)
			(layer "F.Fab")
		)
		(fp_line
			(start -0.299974 -0.150114)
			(end 0.299974 -0.150114)
			(stroke
				(width 0.1)
				(type default)
			)
			(layer "F.Fab")
		)
		(fp_line
			(start 0.299974 0.150114)
			(end -0.299974 0.150114)
			(stroke
				(width 0.1)
				(type default)
			)
			(layer "F.Fab")
		)
		(fp_line
			(start -0.299974 0.150114)
			(end -0.299974 -0.150114)
			(stroke
				(width 0.1)
				(type default)
			)
			(layer "F.Fab")
		)
		(pad "1" smd rect
			(at -0.2667 0 90)
			(size 0.3048 0.381)
			(layers "F.Cu" "F.Mask" "F.Paste")
			(net "P5E_PEX2_STN6_TX_DN<108>")
		)
		(pad "2" smd rect
			(at 0.2667 0 90)
			(size 0.3048 0.381)
			(layers "F.Cu" "F.Mask" "F.Paste")
			(net "P5E_PEX2_STN6_TX_C_DN<108>")
		)
	)
	(footprint ""
		(layer "F.Cu")
		(at 264.611358 -296.445432 -90)
		(property "Reference" "R4578"
			(at 0 0 270)
			(layer "F.SilkS")
			(hide yes)
			(effects
				(font
					(size 1.27 1.27)
				)
			)
		)
		(property "Value" ""
			(at 0 0 270)
			(layer "F.Fab")
			(effects
				(font
					(size 1.27 1.27)
				)
			)
		)
		(duplicate_pad_numbers_are_jumpers no)
		(fp_line
			(start -0.7874 0.4064)
			(end -0.7874 -0.4064)
			(stroke
				(width 0.1524)
				(type default)
			)
			(layer "F.SilkS")
		)
		(fp_line
			(start 0.7874 0.4064)
			(end -0.7874 0.4064)
			(stroke
				(width 0.1524)
				(type default)
			)
			(layer "F.SilkS")
		)
		(fp_line
			(start -0.7874 -0.4064)
			(end 0.7874 -0.4064)
			(stroke
				(width 0.1524)
				(type default)
			)
			(layer "F.SilkS")
		)
		(fp_line
			(start 0.7874 -0.4064)
			(end 0.7874 0.4064)
			(stroke
				(width 0.1524)
				(type default)
			)
			(layer "F.SilkS")
		)
		(fp_line
			(start -0.67945 0.3048)
			(end -0.67945 -0.305054)
			(stroke
				(width 0.1)
				(type default)
			)
			(layer "F.Fab")
		)
		(fp_line
			(start -0.12065 0.3048)
			(end -0.67945 0.3048)
			(stroke
				(width 0.1)
				(type default)
			)
			(layer "F.Fab")
		)
		(fp_line
			(start 0.120396 0.3048)
			(end 0.120396 0.2794)
			(stroke
				(width 0.1)
				(type default)
			)
			(layer "F.Fab")
		)
		(fp_line
			(start 0.67945 0.3048)
			(end 0.120396 0.3048)
			(stroke
				(width 0.1)
				(type default)
			)
			(layer "F.Fab")
		)
		(fp_line
			(start -0.12065 0.2794)
			(end -0.12065 0.3048)
			(stroke
				(width 0.1)
				(type default)
			)
			(layer "F.Fab")
		)
		(fp_line
			(start 0.120396 0.2794)
			(end -0.12065 0.2794)
			(stroke
				(width 0.1)
				(type default)
			)
			(layer "F.Fab")
		)
		(fp_line
			(start -0.12065 -0.2794)
			(end 0.12065 -0.2794)
			(stroke
				(width 0.1)
				(type default)
			)
			(layer "F.Fab")
		)
		(fp_line
			(start 0.12065 -0.2794)
			(end 0.12065 -0.3048)
			(stroke
				(width 0.1)
				(type default)
			)
			(layer "F.Fab")
		)
		(fp_line
			(start 0.12065 -0.3048)
			(end 0.67945 -0.3048)
			(stroke
				(width 0.1)
				(type default)
			)
			(layer "F.Fab")
		)
		(fp_line
			(start 0.67945 -0.3048)
			(end 0.67945 0.3048)
			(stroke
				(width 0.1)
				(type default)
			)
			(layer "F.Fab")
		)
		(fp_line
			(start -0.67945 -0.305054)
			(end -0.12065 -0.305054)
			(stroke
				(width 0.1)
				(type default)
			)
			(layer "F.Fab")
		)
		(fp_line
			(start -0.12065 -0.305054)
			(end -0.12065 -0.2794)
			(stroke
				(width 0.1)
				(type default)
			)
			(layer "F.Fab")
		)
		(pad "1" smd circle
			(at -0.40005 0 270)
			(size 0 0)
			(layers "F.Cu" "F.Mask" "F.Paste")
			(net "PCEPLL0_VDDA18_PEX2")
		)
		(pad "2" smd circle
			(at 0.40005 0 270)
			(size 0 0)
			(layers "F.Cu" "F.Mask" "F.Paste")
			(net "PCEPLL0_VDDA18_PEX2_R")
		)
	)
)
